(kicad_pcb
	(version 20241229)
	(generator "pcbnew")
	(generator_version "9.0")
	(general
		(thickness 1.6296)
		(legacy_teardrops no)
	)
	(paper "A3")
	(title_block
		(title "Thunderbolt to 10GbE adapter")
		(date "2026-04-21")
		(rev "1.1.0")
		(company "Antmicro Ltd")
		(comment 1 "www.antmicro.com")
		(comment 9 "footprints 379-382 of 703")
	)
	(layers
		(0 "F.Cu" signal)
		(4 "In1.Cu" signal)
		(6 "In2.Cu" signal)
		(8 "In3.Cu" signal)
		(10 "In4.Cu" signal)
		(12 "In5.Cu" signal)
		(14 "In6.Cu" signal)
		(2 "B.Cu" signal)
		(9 "F.Adhes" user "F.Adhesive")
		(11 "B.Adhes" user "B.Adhesive")
		(13 "F.Paste" user)
		(15 "B.Paste" user)
		(5 "F.SilkS" user "F.Silkscreen")
		(7 "B.SilkS" user "B.Silkscreen")
		(1 "F.Mask" user)
		(3 "B.Mask" user)
		(17 "Dwgs.User" user "User.Drawings")
		(19 "Cmts.User" user "User.Comments")
		(21 "Eco1.User" user "User.Eco1")
		(23 "Eco2.User" user "User.Eco2")
		(25 "Edge.Cuts" user)
		(27 "Margin" user)
		(31 "F.CrtYd" user "F.Courtyard")
		(29 "B.CrtYd" user "B.Courtyard")
		(35 "F.Fab" user)
		(33 "B.Fab" user)
	)
	(footprint "antmicro-footprints:C_Pol_EIA-A"
		(layer "B.Cu")
		(at 155 99.75 180)
		(property "Reference" "C77"
			(at 2 0 0)
			(layer "B.SilkS")
			(effects
				(font
					(size 0.7 0.7)
					(thickness 0.15)
				)
				(justify left bottom mirror)
			)
		)
		(property "Value" "C_Pol_100u_6V_KEMET-T490-A"
			(at 0 -2 0)
			(layer "B.Fab")
			(effects
				(font
					(size 0.7 0.7)
					(thickness 0.15)
				)
				(justify left bottom mirror)
			)
		)
		(property "Datasheet" "https://www.kemet.com/en/us/capacitors/product/T490A107M006ATE800.html"
			(at 0 0 0)
			(layer "B.Fab")
			(hide yes)
			(effects
				(font
					(size 1.27 1.27)
					(thickness 0.15)
				)
				(justify mirror)
			)
		)
		(property "Description" "Surface Mount Tantalum Capacitor,  Solid SMD 6V 100uF 1206 20% ESR=800mOhms"
			(at 0 0 0)
			(layer "B.Fab")
			(hide yes)
			(effects
				(font
					(size 1.27 1.27)
					(thickness 0.15)
				)
				(justify mirror)
			)
		)
		(property "Val" "100u"
			(at 0 0 180)
			(unlocked yes)
			(layer "B.Fab")
			(hide yes)
			(effects
				(font
					(size 1 1)
					(thickness 0.15)
				)
				(justify mirror)
			)
		)
		(property "MPN" "T490A107M006ATE800"
			(at 0 0 180)
			(unlocked yes)
			(layer "B.Fab")
			(hide yes)
			(effects
				(font
					(size 1 1)
					(thickness 0.15)
				)
				(justify mirror)
			)
		)
		(property "Manufacturer" "KEMET"
			(at 0 0 180)
			(unlocked yes)
			(layer "B.Fab")
			(hide yes)
			(effects
				(font
					(size 1 1)
					(thickness 0.15)
				)
				(justify mirror)
			)
		)
		(property "License" "Apache-2.0"
			(at 0 0 180)
			(unlocked yes)
			(layer "B.Fab")
			(hide yes)
			(effects
				(font
					(size 1 1)
					(thickness 0.15)
				)
				(justify mirror)
			)
		)
		(property "Author" "Antmicro"
			(at 0 0 180)
			(unlocked yes)
			(layer "B.Fab")
			(hide yes)
			(effects
				(font
					(size 1 1)
					(thickness 0.15)
				)
				(justify mirror)
			)
		)
		(property "Voltage" "6V"
			(at 0 0 180)
			(unlocked yes)
			(layer "B.Fab")
			(hide yes)
			(effects
				(font
					(size 1 1)
					(thickness 0.15)
				)
				(justify mirror)
			)
		)
		(property "Dielectric" "template_dielectric"
			(at 0 0 180)
			(unlocked yes)
			(layer "B.Fab")
			(hide yes)
			(effects
				(font
					(size 1 1)
					(thickness 0.15)
				)
				(justify mirror)
			)
		)
		(sheetname "/X710-AT2 power/")
		(sheetfile "x710-at2-power.kicad_sch")
		(attr smd)
		(fp_line
			(start 1.5 0.75)
			(end 1.5 0.85)
			(stroke
				(width 0.12)
				(type solid)
			)
			(layer "B.SilkS")
		)
		(fp_line
			(start 1.5 -0.75)
			(end 1.5 -0.85)
			(stroke
				(width 0.12)
				(type solid)
			)
			(layer "B.SilkS")
		)
		(fp_line
			(start 1.5 -0.85)
			(end -1.5 -0.85)
			(stroke
				(width 0.12)
				(type solid)
			)
			(layer "B.SilkS")
		)
		(fp_line
			(start -1.5 0.85)
			(end 1.5 0.85)
			(stroke
				(width 0.12)
				(type solid)
			)
			(layer "B.SilkS")
		)
		(fp_line
			(start -1.5 0.75)
			(end -1.5 0.85)
			(stroke
				(width 0.12)
				(type solid)
			)
			(layer "B.SilkS")
		)
		(fp_line
			(start -1.5 -0.75)
			(end -1.5 -0.85)
			(stroke
				(width 0.12)
				(type solid)
			)
			(layer "B.SilkS")
		)
		(fp_line
			(start -1.95 1.25)
			(end -1.95 0.95)
			(stroke
				(width 0.12)
				(type solid)
			)
			(layer "B.SilkS")
		)
		(fp_line
			(start -2.1 1.1)
			(end -1.8 1.1)
			(stroke
				(width 0.12)
				(type solid)
			)
			(layer "B.SilkS")
		)
		(fp_line
			(start 2.05 0.85)
			(end 2.05 -0.85)
			(stroke
				(width 0.05)
				(type solid)
			)
			(layer "B.CrtYd")
		)
		(fp_line
			(start 2.05 0.85)
			(end 1.7 0.85)
			(stroke
				(width 0.05)
				(type solid)
			)
			(layer "B.CrtYd")
		)
		(fp_line
			(start 2.05 -0.85)
			(end 1.7 -0.85)
			(stroke
				(width 0.05)
				(type solid)
			)
			(layer "B.CrtYd")
		)
		(fp_line
			(start 1.7 1.05)
			(end -1.7 1.05)
			(stroke
				(width 0.05)
				(type solid)
			)
			(layer "B.CrtYd")
		)
		(fp_line
			(start 1.7 0.85)
			(end 1.7 1.05)
			(stroke
				(width 0.05)
				(type solid)
			)
			(layer "B.CrtYd")
		)
		(fp_line
			(start 1.7 -1.05)
			(end 1.7 -0.85)
			(stroke
				(width 0.05)
				(type solid)
			)
			(layer "B.CrtYd")
		)
		(fp_line
			(start 1.7 -1.05)
			(end -1.7 -1.05)
			(stroke
				(width 0.05)
				(type solid)
			)
			(layer "B.CrtYd")
		)
		(fp_line
			(start -1.7 0.85)
			(end -1.7 1.05)
			(stroke
				(width 0.05)
				(type solid)
			)
			(layer "B.CrtYd")
		)
		(fp_line
			(start -1.7 0.85)
			(end -2.05 0.85)
			(stroke
				(width 0.05)
				(type solid)
			)
			(layer "B.CrtYd")
		)
		(fp_line
			(start -1.7 -0.85)
			(end -2.05 -0.85)
			(stroke
				(width 0.05)
				(type solid)
			)
			(layer "B.CrtYd")
		)
		(fp_line
			(start -1.7 -1.05)
			(end -1.7 -0.85)
			(stroke
				(width 0.05)
				(type solid)
			)
			(layer "B.CrtYd")
		)
		(fp_line
			(start -2.05 0.85)
			(end -2.05 -0.85)
			(stroke
				(width 0.05)
				(type solid)
			)
			(layer "B.CrtYd")
		)
		(fp_rect
			(start -1.601 0.802)
			(end 1.6 -0.8)
			(stroke
				(width 0.1)
				(type solid)
			)
			(fill no)
			(layer "B.Fab")
		)
		(fp_text user "${REFERENCE}"
			(at -2.1 -4.198 0)
			(layer "B.Fab")
			(effects
				(font
					(size 0.7 0.7)
					(thickness 0.15)
				)
				(justify left bottom mirror)
			)
		)
		(fp_text user "Author: Antmicro"
			(at -2.1 -6.198 0)
			(layer "B.Fab")
			(effects
				(font
					(size 0.7 0.7)
					(thickness 0.15)
				)
				(justify left bottom mirror)
			)
		)
		(fp_text user "License: Apache-2.0"
			(at -2.1 -5.198 0)
			(layer "B.Fab")
			(effects
				(font
					(size 0.7 0.7)
					(thickness 0.15)
				)
				(justify left bottom mirror)
			)
		)
		(pad "1" smd roundrect
			(at -1.2 0 180)
			(size 1.2 1.2)
			(layers "B.Cu" "B.Mask" "B.Paste")
			(roundrect_rratio 0.1)
			(net 136 "+1V0")
			(pintype "passive")
		)
		(pad "2" smd roundrect
			(at 1.2 0 180)
			(size 1.2 1.2)
			(layers "B.Cu" "B.Mask" "B.Paste")
			(roundrect_rratio 0.1)
			(net 23 "GND")
			(pintype "passive")
		)
	)
	(footprint "antmicro-footprints:C_0402_1005Metric"
		(layer "B.Cu")
		(at 129.474998 120.05 -90)
		(descr "Capacitor SMD 0402")
		(tags "capacitor SMD 0402")
		(property "Reference" "C72"
			(at -7.700002 -21.900002 90)
			(layer "B.SilkS")
			(effects
				(font
					(size 0.7 0.7)
					(thickness 0.15)
				)
				(justify mirror)
			)
		)
		(property "Value" "C_1u_0402"
			(at -1.022927 -2.155213 90)
			(layer "B.Fab")
			(effects
				(font
					(size 0.7 0.7)
					(thickness 0.15)
				)
				(justify left bottom mirror)
			)
		)
		(property "Datasheet" "https://product.tdk.com/en/search/capacitor/ceramic/mlcc/info?part_no=C1005X6S1A105K050BC"
			(at 0 0 90)
			(layer "B.Fab")
			(hide yes)
			(effects
				(font
					(size 1.27 1.27)
					(thickness 0.15)
				)
				(justify mirror)
			)
		)
		(property "Description" "SMD Multilayer Ceramic Capacitor, 1 µF, 10 V, 0402 [1005 Metric], ± 10%, X6S, C"
			(at 0 0 90)
			(layer "B.Fab")
			(hide yes)
			(effects
				(font
					(size 1.27 1.27)
					(thickness 0.15)
				)
				(justify mirror)
			)
		)
		(property "MPN" "C1005X6S1A105K050BC"
			(at 0 0 270)
			(unlocked yes)
			(layer "B.Fab")
			(hide yes)
			(effects
				(font
					(size 1 1)
					(thickness 0.15)
				)
				(justify mirror)
			)
		)
		(property "Manufacturer" "TDK"
			(at 0 0 270)
			(unlocked yes)
			(layer "B.Fab")
			(hide yes)
			(effects
				(font
					(size 1 1)
					(thickness 0.15)
				)
				(justify mirror)
			)
		)
		(property "License" "Apache-2.0"
			(at 0 0 270)
			(unlocked yes)
			(layer "B.Fab")
			(hide yes)
			(effects
				(font
					(size 1 1)
					(thickness 0.15)
				)
				(justify mirror)
			)
		)
		(property "Val" "1u"
			(at 0 0 270)
			(unlocked yes)
			(layer "B.Fab")
			(hide yes)
			(effects
				(font
					(size 1 1)
					(thickness 0.15)
				)
				(justify mirror)
			)
		)
		(property "Voltage" ""
			(at 0 0 270)
			(unlocked yes)
			(layer "B.Fab")
			(hide yes)
			(effects
				(font
					(size 1 1)
					(thickness 0.15)
				)
				(justify mirror)
			)
		)
		(property "Dielectric" ""
			(at 0 0 270)
			(unlocked yes)
			(layer "B.Fab")
			(hide yes)
			(effects
				(font
					(size 1 1)
					(thickness 0.15)
				)
				(justify mirror)
			)
		)
		(property "Author" "Antmicro"
			(at 0 0 270)
			(unlocked yes)
			(layer "B.Fab")
			(hide yes)
			(effects
				(font
					(size 1 1)
					(thickness 0.15)
				)
				(justify mirror)
			)
		)
		(sheetname "/TB Controller - Power/")
		(sheetfile "tb-power.kicad_sch")
		(attr smd)
		(fp_rect
			(start -0.925 0.47)
			(end 0.925 -0.47)
			(stroke
				(width 0.05)
				(type default)
			)
			(fill no)
			(layer "B.CrtYd")
		)
		(fp_line
			(start -0.494 0.25)
			(end 0.504 0.25)
			(stroke
				(width 0.15)
				(type solid)
			)
			(layer "B.Fab")
		)
		(fp_line
			(start 0.504 0.25)
			(end 0.504 -0.248)
			(stroke
				(width 0.15)
				(type solid)
			)
			(layer "B.Fab")
		)
		(fp_line
			(start -0.494 -0.248)
			(end -0.494 0.25)
			(stroke
				(width 0.15)
				(type solid)
			)
			(layer "B.Fab")
		)
		(fp_line
			(start 0.504 -0.248)
			(end -0.494 -0.248)
			(stroke
				(width 0.15)
				(type solid)
			)
			(layer "B.Fab")
		)
		(fp_text user "Author: Antmicro"
			(at -0.939 -3.399 90)
			(layer "B.Fab")
			(effects
				(font
					(size 0.7 0.7)
					(thickness 0.15)
				)
				(justify left bottom mirror)
			)
		)
		(fp_text user "${REFERENCE}"
			(at -0.939 -4.599 90)
			(layer "B.Fab")
			(effects
				(font
					(size 0.7 0.7)
					(thickness 0.15)
				)
				(justify left bottom mirror)
			)
		)
		(fp_text user "License: Apache-2.0"
			(at -0.939 -5.799 90)
			(layer "B.Fab")
			(effects
				(font
					(size 0.7 0.7)
					(thickness 0.15)
				)
				(justify left bottom mirror)
			)
		)
		(pad "1" smd roundrect
			(at -0.48 0 270)
			(size 0.59 0.64)
			(layers "B.Cu" "B.Mask" "B.Paste")
			(roundrect_rratio 0.25)
			(net 23 "GND")
			(pintype "passive")
		)
		(pad "2" smd roundrect
			(at 0.48 0 270)
			(size 0.59 0.64)
			(layers "B.Cu" "B.Mask" "B.Paste")
			(roundrect_rratio 0.25)
			(net 404 "Net-(C58-Pad2)")
			(pintype "passive")
		)
	)
	(footprint "antmicro-footprints:C_0402_1005Metric"
		(layer "B.Cu")
		(at 131.424998 122.000002 -90)
		(descr "Capacitor SMD 0402")
		(tags "capacitor SMD 0402")
		(property "Reference" "C73"
			(at -7.700002 -21.900002 90)
			(layer "B.SilkS")
			(effects
				(font
					(size 0.7 0.7)
					(thickness 0.15)
				)
				(justify mirror)
			)
		)
		(property "Value" "C_1u_0402"
			(at -1.022927 -2.155213 90)
			(layer "B.Fab")
			(effects
				(font
					(size 0.7 0.7)
					(thickness 0.15)
				)
				(justify left bottom mirror)
			)
		)
		(property "Datasheet" "https://product.tdk.com/en/search/capacitor/ceramic/mlcc/info?part_no=C1005X6S1A105K050BC"
			(at 0 0 90)
			(layer "B.Fab")
			(hide yes)
			(effects
				(font
					(size 1.27 1.27)
					(thickness 0.15)
				)
				(justify mirror)
			)
		)
		(property "Description" "SMD Multilayer Ceramic Capacitor, 1 µF, 10 V, 0402 [1005 Metric], ± 10%, X6S, C"
			(at 0 0 90)
			(layer "B.Fab")
			(hide yes)
			(effects
				(font
					(size 1.27 1.27)
					(thickness 0.15)
				)
				(justify mirror)
			)
		)
		(property "MPN" "C1005X6S1A105K050BC"
			(at 0 0 270)
			(unlocked yes)
			(layer "B.Fab")
			(hide yes)
			(effects
				(font
					(size 1 1)
					(thickness 0.15)
				)
				(justify mirror)
			)
		)
		(property "Manufacturer" "TDK"
			(at 0 0 270)
			(unlocked yes)
			(layer "B.Fab")
			(hide yes)
			(effects
				(font
					(size 1 1)
					(thickness 0.15)
				)
				(justify mirror)
			)
		)
		(property "License" "Apache-2.0"
			(at 0 0 270)
			(unlocked yes)
			(layer "B.Fab")
			(hide yes)
			(effects
				(font
					(size 1 1)
					(thickness 0.15)
				)
				(justify mirror)
			)
		)
		(property "Val" "1u"
			(at 0 0 270)
			(unlocked yes)
			(layer "B.Fab")
			(hide yes)
			(effects
				(font
					(size 1 1)
					(thickness 0.15)
				)
				(justify mirror)
			)
		)
		(property "Voltage" ""
			(at 0 0 270)
			(unlocked yes)
			(layer "B.Fab")
			(hide yes)
			(effects
				(font
					(size 1 1)
					(thickness 0.15)
				)
				(justify mirror)
			)
		)
		(property "Dielectric" ""
			(at 0 0 270)
			(unlocked yes)
			(layer "B.Fab")
			(hide yes)
			(effects
				(font
					(size 1 1)
					(thickness 0.15)
				)
				(justify mirror)
			)
		)
		(property "Author" "Antmicro"
			(at 0 0 270)
			(unlocked yes)
			(layer "B.Fab")
			(hide yes)
			(effects
				(font
					(size 1 1)
					(thickness 0.15)
				)
				(justify mirror)
			)
		)
		(sheetname "/TB Controller - Power/")
		(sheetfile "tb-power.kicad_sch")
		(attr smd)
		(fp_rect
			(start -0.925 0.47)
			(end 0.925 -0.47)
			(stroke
				(width 0.05)
				(type default)
			)
			(fill no)
			(layer "B.CrtYd")
		)
		(fp_line
			(start -0.494 0.25)
			(end 0.504 0.25)
			(stroke
				(width 0.15)
				(type solid)
			)
			(layer "B.Fab")
		)
		(fp_line
			(start 0.504 0.25)
			(end 0.504 -0.248)
			(stroke
				(width 0.15)
				(type solid)
			)
			(layer "B.Fab")
		)
		(fp_line
			(start -0.494 -0.248)
			(end -0.494 0.25)
			(stroke
				(width 0.15)
				(type solid)
			)
			(layer "B.Fab")
		)
		(fp_line
			(start 0.504 -0.248)
			(end -0.494 -0.248)
			(stroke
				(width 0.15)
				(type solid)
			)
			(layer "B.Fab")
		)
		(fp_text user "License: Apache-2.0"
			(at -0.939 -5.799 90)
			(layer "B.Fab")
			(effects
				(font
					(size 0.7 0.7)
					(thickness 0.15)
				)
				(justify left bottom mirror)
			)
		)
		(fp_text user "${REFERENCE}"
			(at -0.939 -4.599 90)
			(layer "B.Fab")
			(effects
				(font
					(size 0.7 0.7)
					(thickness 0.15)
				)
				(justify left bottom mirror)
			)
		)
		(fp_text user "Author: Antmicro"
			(at -0.939 -3.399 90)
			(layer "B.Fab")
			(effects
				(font
					(size 0.7 0.7)
					(thickness 0.15)
				)
				(justify left bottom mirror)
			)
		)
		(pad "1" smd roundrect
			(at -0.48 0 270)
			(size 0.59 0.64)
			(layers "B.Cu" "B.Mask" "B.Paste")
			(roundrect_rratio 0.25)
			(net 23 "GND")
			(pintype "passive")
		)
		(pad "2" smd roundrect
			(at 0.48 0 270)
			(size 0.59 0.64)
			(layers "B.Cu" "B.Mask" "B.Paste")
			(roundrect_rratio 0.25)
			(net 179 "Net-(U4A-VCC3P3_LC)")
			(pintype "passive")
		)
	)
	(footprint "antmicro-footprints:C_0402_1005Metric"
		(layer "B.Cu")
		(at 159.381866 80.685116 -90)
		(descr "Capacitor SMD 0402")
		(tags "capacitor SMD 0402")
		(property "Reference" "C194"
			(at 8.814884 -20.618136 90)
			(layer "B.SilkS")
			(effects
				(font
					(size 0.7 0.7)
					(thickness 0.15)
				)
				(justify mirror)
			)
		)
		(property "Value" "C_1u_25V_0402"
			(at -1.022927 -2.155213 90)
			(layer "B.Fab")
			(effects
				(font
					(size 0.7 0.7)
					(thickness 0.15)
				)
				(justify left bottom mirror)
			)
		)
		(property "Datasheet" "https://www.murata.com/products/productdetail?partno=GRM155R61E105KE11%23"
			(at 0 0 90)
			(layer "B.Fab")
			(hide yes)
			(effects
				(font
					(size 1.27 1.27)
					(thickness 0.15)
				)
				(justify mirror)
			)
		)
		(property "Description" "SMD Multilayer Ceramic Capacitor, 1 µF, 25 V, 0402 [1005 Metric], ± 10%, X5R, GRM Series"
			(at 0 0 90)
			(layer "B.Fab")
			(hide yes)
			(effects
				(font
					(size 1.27 1.27)
					(thickness 0.15)
				)
				(justify mirror)
			)
		)
		(property "MPN" "GRM155R61E105KE11J"
			(at 0 0 270)
			(unlocked yes)
			(layer "B.Fab")
			(hide yes)
			(effects
				(font
					(size 1 1)
					(thickness 0.15)
				)
				(justify mirror)
			)
		)
		(property "Manufacturer" "Murata"
			(at 0 0 270)
			(unlocked yes)
			(layer "B.Fab")
			(hide yes)
			(effects
				(font
					(size 1 1)
					(thickness 0.15)
				)
				(justify mirror)
			)
		)
		(property "License" "Apache-2.0"
			(at 0 0 270)
			(unlocked yes)
			(layer "B.Fab")
			(hide yes)
			(effects
				(font
					(size 1 1)
					(thickness 0.15)
				)
				(justify mirror)
			)
		)
		(property "Author" "Antmicro"
			(at 0 0 270)
			(unlocked yes)
			(layer "B.Fab")
			(hide yes)
			(effects
				(font
					(size 1 1)
					(thickness 0.15)
				)
				(justify mirror)
			)
		)
		(property "Val" "1u"
			(at 0 0 270)
			(unlocked yes)
			(layer "B.Fab")
			(hide yes)
			(effects
				(font
					(size 1 1)
					(thickness 0.15)
				)
				(justify mirror)
			)
		)
		(property "Voltage" "25V"
			(at 0 0 270)
			(unlocked yes)
			(layer "B.Fab")
			(hide yes)
			(effects
				(font
					(size 1 1)
					(thickness 0.15)
				)
				(justify mirror)
			)
		)
		(property "Dielectric" "X5R"
			(at 0 0 270)
			(unlocked yes)
			(layer "B.Fab")
			(hide yes)
			(effects
				(font
					(size 1 1)
					(thickness 0.15)
				)
				(justify mirror)
			)
		)
		(sheetname "/X710-AT2 power/")
		(sheetfile "x710-at2-power.kicad_sch")
		(attr smd)
		(fp_rect
			(start -0.925 0.47)
			(end 0.925 -0.47)
			(stroke
				(width 0.05)
				(type default)
			)
			(fill no)
			(layer "B.CrtYd")
		)
		(fp_line
			(start -0.494 0.25)
			(end 0.504 0.25)
			(stroke
				(width 0.15)
				(type solid)
			)
			(layer "B.Fab")
		)
		(fp_line
			(start 0.504 0.25)
			(end 0.504 -0.248)
			(stroke
				(width 0.15)
				(type solid)
			)
			(layer "B.Fab")
		)
		(fp_line
			(start -0.494 -0.248)
			(end -0.494 0.25)
			(stroke
				(width 0.15)
				(type solid)
			)
			(layer "B.Fab")
		)
		(fp_line
			(start 0.504 -0.248)
			(end -0.494 -0.248)
			(stroke
				(width 0.15)
				(type solid)
			)
			(layer "B.Fab")
		)
		(fp_text user "${REFERENCE}"
			(at -0.939 -4.599 90)
			(layer "B.Fab")
			(effects
				(font
					(size 0.7 0.7)
					(thickness 0.15)
				)
				(justify left bottom mirror)
			)
		)
		(fp_text user "License: Apache-2.0"
			(at -0.939 -5.799 90)
			(layer "B.Fab")
			(effects
				(font
					(size 0.7 0.7)
					(thickness 0.15)
				)
				(justify left bottom mirror)
			)
		)
		(fp_text user "Author: Antmicro"
			(at -0.939 -3.399 90)
			(layer "B.Fab")
			(effects
				(font
					(size 0.7 0.7)
					(thickness 0.15)
				)
				(justify left bottom mirror)
			)
		)
		(pad "1" smd roundrect
			(at -0.48 0 270)
			(size 0.59 0.64)
			(layers "B.Cu" "B.Mask" "B.Paste")
			(roundrect_rratio 0.25)
			(net 23 "GND")
			(pintype "passive")
		)
		(pad "2" smd roundrect
			(at 0.48 0 270)
			(size 0.59 0.64)
			(layers "B.Cu" "B.Mask" "B.Paste")
			(roundrect_rratio 0.25)
			(net 14 "P1_AVDDL")
			(pintype "passive")
		)
	)
)
